(kicad_pcb
	(version 20260206)
	(generator "pcbnew")
	(generator_version "10.0")
	(general
		(thickness 1.6)
		(legacy_teardrops no)
	)
	(paper "A4")
	(title_block
		(title "01162023_DA0F0TEBIF0_F0T_Expander_BD_F_brd_V02_OCP.brd")
		(comment 1 "Grand Teton / footprints 4336-4343 of 9728")
	)
	(layers
		(0 "F.Cu" signal "TOP")
		(4 "In1.Cu" signal "GND")
		(6 "In2.Cu" signal "VCC")
		(8 "In3.Cu" signal "VCC1")
		(10 "In4.Cu" signal "GND1")
		(12 "In5.Cu" signal "IN1")
		(14 "In6.Cu" signal "GND2")
		(16 "In7.Cu" signal "IN2")
		(18 "In8.Cu" signal "GND3")
		(20 "In9.Cu" signal "IN3")
		(22 "In10.Cu" signal "GND4")
		(24 "In11.Cu" signal "IN4")
		(26 "In12.Cu" signal "GND5")
		(28 "In13.Cu" signal "IN5")
		(30 "In14.Cu" signal "GND6")
		(32 "In15.Cu" signal "IN6")
		(34 "In16.Cu" signal "GND7")
		(2 "B.Cu" signal "BOTTOM")
		(9 "F.Adhes" user "F.Adhesive")
		(11 "B.Adhes" user "B.Adhesive")
		(13 "F.Paste" user "Package Geometry/Pastemask Top")
		(15 "B.Paste" user "Package Geometry/Pastemask Bottom")
		(5 "F.SilkS" user "Ref Des/Silkscreen Top")
		(7 "B.SilkS" user "Ref Des/Silkscreen Bottom")
		(1 "F.Mask" user "Board Geometry/Soldermask Top")
		(3 "B.Mask" user "Board Geometry/Soldermask Bottom")
		(17 "Dwgs.User" user "User.Drawings")
		(19 "Cmts.User" user "User.Comments")
		(21 "Eco1.User" user "User.Eco1")
		(23 "Eco2.User" user "User.Eco2")
		(25 "Edge.Cuts" user "Board Geometry/Outline")
		(27 "Margin" user)
		(31 "F.CrtYd" user "Package Geometry/Place Bound Top")
		(29 "B.CrtYd" user "Package Geometry/Place Bound Bottom")
		(35 "F.Fab" user "Ref Des/Assembly Top")
		(33 "B.Fab" user "Ref Des/Assembly Bottom")
	)
	(footprint ""
		(layer "F.Cu")
		(at 187.032392 -343.952322 90)
		(property "Reference" "C378"
			(at 0 0 90)
			(layer "F.SilkS")
			(hide yes)
			(effects
				(font
					(size 1.27 1.27)
				)
			)
		)
		(property "Value" ""
			(at 0 0 90)
			(layer "F.Fab")
			(effects
				(font
					(size 1.27 1.27)
				)
			)
		)
		(duplicate_pad_numbers_are_jumpers no)
		(fp_line
			(start 0.299974 -0.150114)
			(end 0.299974 0.150114)
			(stroke
				(width 0.1)
				(type default)
			)
			(layer "F.Fab")
		)
		(fp_line
			(start -0.299974 -0.150114)
			(end 0.299974 -0.150114)
			(stroke
				(width 0.1)
				(type default)
			)
			(layer "F.Fab")
		)
		(fp_line
			(start 0.299974 0.150114)
			(end -0.299974 0.150114)
			(stroke
				(width 0.1)
				(type default)
			)
			(layer "F.Fab")
		)
		(fp_line
			(start -0.299974 0.150114)
			(end -0.299974 -0.150114)
			(stroke
				(width 0.1)
				(type default)
			)
			(layer "F.Fab")
		)
		(pad "1" smd rect
			(at -0.2667 0 90)
			(size 0.3048 0.381)
			(layers "F.Cu" "F.Mask" "F.Paste")
			(net "P5E_PEX1_STN7_TX_DP<124>")
		)
		(pad "2" smd rect
			(at 0.2667 0 90)
			(size 0.3048 0.381)
			(layers "F.Cu" "F.Mask" "F.Paste")
			(net "P5E_PEX1_STN7_TX_C_DP<124>")
		)
	)
	(footprint ""
		(layer "F.Cu")
		(at 316.908942 -27.04973 180)
		(property "Reference" "C2774"
			(at 0 0 180)
			(layer "F.SilkS")
			(hide yes)
			(effects
				(font
					(size 1.27 1.27)
				)
			)
		)
		(property "Value" ""
			(at 0 0 180)
			(layer "F.Fab")
			(effects
				(font
					(size 1.27 1.27)
				)
			)
		)
		(duplicate_pad_numbers_are_jumpers no)
		(fp_line
			(start 0.7874 0.4064)
			(end -0.7874 0.4064)
			(stroke
				(width 0.1524)
				(type default)
			)
			(layer "F.SilkS")
		)
		(fp_line
			(start 0.7874 -0.4064)
			(end 0.7874 0.4064)
			(stroke
				(width 0.1524)
				(type default)
			)
			(layer "F.SilkS")
		)
		(fp_line
			(start -0.7874 0.4064)
			(end -0.7874 -0.4064)
			(stroke
				(width 0.1524)
				(type default)
			)
			(layer "F.SilkS")
		)
		(fp_line
			(start -0.7874 -0.4064)
			(end 0.7874 -0.4064)
			(stroke
				(width 0.1524)
				(type default)
			)
			(layer "F.SilkS")
		)
		(fp_line
			(start 0.67945 0.3048)
			(end 0.120396 0.3048)
			(stroke
				(width 0.1)
				(type default)
			)
			(layer "F.Fab")
		)
		(fp_line
			(start 0.67945 -0.3048)
			(end 0.67945 0.3048)
			(stroke
				(width 0.1)
				(type default)
			)
			(layer "F.Fab")
		)
		(fp_line
			(start 0.12065 -0.2794)
			(end 0.12065 -0.3048)
			(stroke
				(width 0.1)
				(type default)
			)
			(layer "F.Fab")
		)
		(fp_line
			(start 0.12065 -0.3048)
			(end 0.67945 -0.3048)
			(stroke
				(width 0.1)
				(type default)
			)
			(layer "F.Fab")
		)
		(fp_line
			(start 0.120396 0.3048)
			(end 0.120396 0.2794)
			(stroke
				(width 0.1)
				(type default)
			)
			(layer "F.Fab")
		)
		(fp_line
			(start 0.120396 0.2794)
			(end -0.12065 0.2794)
			(stroke
				(width 0.1)
				(type default)
			)
			(layer "F.Fab")
		)
		(fp_line
			(start -0.12065 0.3048)
			(end -0.67945 0.3048)
			(stroke
				(width 0.1)
				(type default)
			)
			(layer "F.Fab")
		)
		(fp_line
			(start -0.12065 0.2794)
			(end -0.12065 0.3048)
			(stroke
				(width 0.1)
				(type default)
			)
			(layer "F.Fab")
		)
		(fp_line
			(start -0.12065 -0.2794)
			(end 0.12065 -0.2794)
			(stroke
				(width 0.1)
				(type default)
			)
			(layer "F.Fab")
		)
		(fp_line
			(start -0.12065 -0.305054)
			(end -0.12065 -0.2794)
			(stroke
				(width 0.1)
				(type default)
			)
			(layer "F.Fab")
		)
		(fp_line
			(start -0.67945 0.3048)
			(end -0.67945 -0.305054)
			(stroke
				(width 0.1)
				(type default)
			)
			(layer "F.Fab")
		)
		(fp_line
			(start -0.67945 -0.305054)
			(end -0.12065 -0.305054)
			(stroke
				(width 0.1)
				(type default)
			)
			(layer "F.Fab")
		)
		(pad "1" smd circle
			(at -0.40005 0 180)
			(size 0 0)
			(layers "F.Cu" "F.Mask" "F.Paste")
			(net "PRSNT_SSD11_R_N")
		)
		(pad "2" smd circle
			(at 0.40005 0 180)
			(size 0 0)
			(layers "F.Cu" "F.Mask" "F.Paste")
			(net "GND")
		)
	)
	(footprint ""
		(layer "F.Cu")
		(at 82.661506 -156.111194 180)
		(property "Reference" "C1"
			(at 0 0 180)
			(layer "F.SilkS")
			(hide yes)
			(effects
				(font
					(size 1.27 1.27)
				)
			)
		)
		(property "Value" ""
			(at 0 0 180)
			(layer "F.Fab")
			(effects
				(font
					(size 1.27 1.27)
				)
			)
		)
		(duplicate_pad_numbers_are_jumpers no)
		(fp_line
			(start 0.299974 0.150114)
			(end -0.299974 0.150114)
			(stroke
				(width 0.1)
				(type default)
			)
			(layer "F.Fab")
		)
		(fp_line
			(start 0.299974 -0.150114)
			(end 0.299974 0.150114)
			(stroke
				(width 0.1)
				(type default)
			)
			(layer "F.Fab")
		)
		(fp_line
			(start -0.299974 0.150114)
			(end -0.299974 -0.150114)
			(stroke
				(width 0.1)
				(type default)
			)
			(layer "F.Fab")
		)
		(fp_line
			(start -0.299974 -0.150114)
			(end 0.299974 -0.150114)
			(stroke
				(width 0.1)
				(type default)
			)
			(layer "F.Fab")
		)
		(pad "1" smd rect
			(at -0.2667 0 180)
			(size 0.3048 0.381)
			(layers "F.Cu" "F.Mask" "F.Paste")
			(net "P5E_PEX0_STN0_TX_DP<15>")
		)
		(pad "2" smd rect
			(at 0.2667 0 180)
			(size 0.3048 0.381)
			(layers "F.Cu" "F.Mask" "F.Paste")
			(net "P5E_PEX0_STN0_TX_C_DP<15>")
		)
	)
	(footprint ""
		(layer "F.Cu")
		(at 37.248084 -102.009702)
		(property "Reference" "C62"
			(at 0 0 0)
			(layer "F.SilkS")
			(hide yes)
			(effects
				(font
					(size 1.27 1.27)
				)
			)
		)
		(property "Value" ""
			(at 0 0 0)
			(layer "F.Fab")
			(effects
				(font
					(size 1.27 1.27)
				)
			)
		)
		(duplicate_pad_numbers_are_jumpers no)
		(fp_line
			(start -0.299974 -0.150114)
			(end 0.299974 -0.150114)
			(stroke
				(width 0.1)
				(type default)
			)
			(layer "F.Fab")
		)
		(fp_line
			(start -0.299974 0.150114)
			(end -0.299974 -0.150114)
			(stroke
				(width 0.1)
				(type default)
			)
			(layer "F.Fab")
		)
		(fp_line
			(start 0.299974 -0.150114)
			(end 0.299974 0.150114)
			(stroke
				(width 0.1)
				(type default)
			)
			(layer "F.Fab")
		)
		(fp_line
			(start 0.299974 0.150114)
			(end -0.299974 0.150114)
			(stroke
				(width 0.1)
				(type default)
			)
			(layer "F.Fab")
		)
		(pad "1" smd rect
			(at -0.2667 0)
			(size 0.3048 0.381)
			(layers "F.Cu" "F.Mask" "F.Paste")
			(net "P5E_PEX0_STN1_TX_DP<17>")
		)
		(pad "2" smd rect
			(at 0.2667 0)
			(size 0.3048 0.381)
			(layers "F.Cu" "F.Mask" "F.Paste")
			(net "P5E_PEX0_STN1_TX_C_DP<17>")
		)
	)
	(footprint ""
		(layer "F.Cu")
		(at 159.892492 -28.225242 180)
		(property "Reference" "C291"
			(at 0 0 180)
			(layer "F.SilkS")
			(hide yes)
			(effects
				(font
					(size 1.27 1.27)
				)
			)
		)
		(property "Value" ""
			(at 0 0 180)
			(layer "F.Fab")
			(effects
				(font
					(size 1.27 1.27)
				)
			)
		)
		(duplicate_pad_numbers_are_jumpers no)
		(fp_line
			(start 0.299974 0.150114)
			(end -0.299974 0.150114)
			(stroke
				(width 0.1)
				(type default)
			)
			(layer "F.Fab")
		)
		(fp_line
			(start 0.299974 -0.150114)
			(end 0.299974 0.150114)
			(stroke
				(width 0.1)
				(type default)
			)
			(layer "F.Fab")
		)
		(fp_line
			(start -0.299974 0.150114)
			(end -0.299974 -0.150114)
			(stroke
				(width 0.1)
				(type default)
			)
			(layer "F.Fab")
		)
		(fp_line
			(start -0.299974 -0.150114)
			(end 0.299974 -0.150114)
			(stroke
				(width 0.1)
				(type default)
			)
			(layer "F.Fab")
		)
		(pad "1" smd rect
			(at -0.2667 0 180)
			(size 0.3048 0.381)
			(layers "F.Cu" "F.Mask" "F.Paste")
			(net "P5E_PEX1_STN2_TX_DN<40>")
		)
		(pad "2" smd rect
			(at 0.2667 0 180)
			(size 0.3048 0.381)
			(layers "F.Cu" "F.Mask" "F.Paste")
			(net "P5E_PEX1_STN2_TX_C_DN<40>")
		)
	)
	(footprint ""
		(layer "F.Cu")
		(at 241.56416 -55.81142 90)
		(property "Reference" "PC554"
			(at 0 0 90)
			(layer "F.SilkS")
			(hide yes)
			(effects
				(font
					(size 1.27 1.27)
				)
			)
		)
		(property "Value" ""
			(at 0 0 90)
			(layer "F.Fab")
			(effects
				(font
					(size 1.27 1.27)
				)
			)
		)
		(duplicate_pad_numbers_are_jumpers no)
		(fp_line
			(start 0.7874 -0.4064)
			(end 0.7874 0.4064)
			(stroke
				(width 0.1524)
				(type default)
			)
			(layer "F.SilkS")
		)
		(fp_line
			(start -0.7874 -0.4064)
			(end 0.7874 -0.4064)
			(stroke
				(width 0.1524)
				(type default)
			)
			(layer "F.SilkS")
		)
		(fp_line
			(start 0.7874 0.4064)
			(end -0.7874 0.4064)
			(stroke
				(width 0.1524)
				(type default)
			)
			(layer "F.SilkS")
		)
		(fp_line
			(start -0.7874 0.4064)
			(end -0.7874 -0.4064)
			(stroke
				(width 0.1524)
				(type default)
			)
			(layer "F.SilkS")
		)
		(fp_line
			(start -0.12065 -0.305054)
			(end -0.12065 -0.2794)
			(stroke
				(width 0.1)
				(type default)
			)
			(layer "F.Fab")
		)
		(fp_line
			(start -0.67945 -0.305054)
			(end -0.12065 -0.305054)
			(stroke
				(width 0.1)
				(type default)
			)
			(layer "F.Fab")
		)
		(fp_line
			(start 0.67945 -0.3048)
			(end 0.67945 0.3048)
			(stroke
				(width 0.1)
				(type default)
			)
			(layer "F.Fab")
		)
		(fp_line
			(start 0.12065 -0.3048)
			(end 0.67945 -0.3048)
			(stroke
				(width 0.1)
				(type default)
			)
			(layer "F.Fab")
		)
		(fp_line
			(start 0.12065 -0.2794)
			(end 0.12065 -0.3048)
			(stroke
				(width 0.1)
				(type default)
			)
			(layer "F.Fab")
		)
		(fp_line
			(start -0.12065 -0.2794)
			(end 0.12065 -0.2794)
			(stroke
				(width 0.1)
				(type default)
			)
			(layer "F.Fab")
		)
		(fp_line
			(start 0.120396 0.2794)
			(end -0.12065 0.2794)
			(stroke
				(width 0.1)
				(type default)
			)
			(layer "F.Fab")
		)
		(fp_line
			(start -0.12065 0.2794)
			(end -0.12065 0.3048)
			(stroke
				(width 0.1)
				(type default)
			)
			(layer "F.Fab")
		)
		(fp_line
			(start 0.67945 0.3048)
			(end 0.120396 0.3048)
			(stroke
				(width 0.1)
				(type default)
			)
			(layer "F.Fab")
		)
		(fp_line
			(start 0.120396 0.3048)
			(end 0.120396 0.2794)
			(stroke
				(width 0.1)
				(type default)
			)
			(layer "F.Fab")
		)
		(fp_line
			(start -0.12065 0.3048)
			(end -0.67945 0.3048)
			(stroke
				(width 0.1)
				(type default)
			)
			(layer "F.Fab")
		)
		(fp_line
			(start -0.67945 0.3048)
			(end -0.67945 -0.305054)
			(stroke
				(width 0.1)
				(type default)
			)
			(layer "F.Fab")
		)
		(pad "1" smd circle
			(at -0.40005 0 90)
			(size 0 0)
			(layers "F.Cu" "F.Mask" "F.Paste")
			(net "P3V3_SSD8_SS")
		)
		(pad "2" smd circle
			(at 0.40005 0 90)
			(size 0 0)
			(layers "F.Cu" "F.Mask" "F.Paste")
			(net "GND")
		)
	)
	(footprint ""
		(layer "F.Cu")
		(at 81.002632 -89.1159)
		(property "Reference" "C873"
			(at 0 0 0)
			(layer "F.SilkS")
			(hide yes)
			(effects
				(font
					(size 1.27 1.27)
				)
			)
		)
		(property "Value" ""
			(at 0 0 0)
			(layer "F.Fab")
			(effects
				(font
					(size 1.27 1.27)
				)
			)
		)
		(duplicate_pad_numbers_are_jumpers no)
		(fp_line
			(start -0.7874 -0.4064)
			(end 0.7874 -0.4064)
			(stroke
				(width 0.1524)
				(type default)
			)
			(layer "F.SilkS")
		)
		(fp_line
			(start -0.7874 0.4064)
			(end -0.7874 -0.4064)
			(stroke
				(width 0.1524)
				(type default)
			)
			(layer "F.SilkS")
		)
		(fp_line
			(start 0.7874 -0.4064)
			(end 0.7874 0.4064)
			(stroke
				(width 0.1524)
				(type default)
			)
			(layer "F.SilkS")
		)
		(fp_line
			(start 0.7874 0.4064)
			(end -0.7874 0.4064)
			(stroke
				(width 0.1524)
				(type default)
			)
			(layer "F.SilkS")
		)
		(fp_line
			(start -0.67945 -0.305054)
			(end -0.12065 -0.305054)
			(stroke
				(width 0.1)
				(type default)
			)
			(layer "F.Fab")
		)
		(fp_line
			(start -0.67945 0.3048)
			(end -0.67945 -0.305054)
			(stroke
				(width 0.1)
				(type default)
			)
			(layer "F.Fab")
		)
		(fp_line
			(start -0.12065 -0.305054)
			(end -0.12065 -0.2794)
			(stroke
				(width 0.1)
				(type default)
			)
			(layer "F.Fab")
		)
		(fp_line
			(start -0.12065 -0.2794)
			(end 0.12065 -0.2794)
			(stroke
				(width 0.1)
				(type default)
			)
			(layer "F.Fab")
		)
		(fp_line
			(start -0.12065 0.2794)
			(end -0.12065 0.3048)
			(stroke
				(width 0.1)
				(type default)
			)
			(layer "F.Fab")
		)
		(fp_line
			(start -0.12065 0.3048)
			(end -0.67945 0.3048)
			(stroke
				(width 0.1)
				(type default)
			)
			(layer "F.Fab")
		)
		(fp_line
			(start 0.120396 0.2794)
			(end -0.12065 0.2794)
			(stroke
				(width 0.1)
				(type default)
			)
			(layer "F.Fab")
		)
		(fp_line
			(start 0.120396 0.3048)
			(end 0.120396 0.2794)
			(stroke
				(width 0.1)
				(type default)
			)
			(layer "F.Fab")
		)
		(fp_line
			(start 0.12065 -0.3048)
			(end 0.67945 -0.3048)
			(stroke
				(width 0.1)
				(type default)
			)
			(layer "F.Fab")
		)
		(fp_line
			(start 0.12065 -0.2794)
			(end 0.12065 -0.3048)
			(stroke
				(width 0.1)
				(type default)
			)
			(layer "F.Fab")
		)
		(fp_line
			(start 0.67945 -0.3048)
			(end 0.67945 0.3048)
			(stroke
				(width 0.1)
				(type default)
			)
			(layer "F.Fab")
		)
		(fp_line
			(start 0.67945 0.3048)
			(end 0.120396 0.3048)
			(stroke
				(width 0.1)
				(type default)
			)
			(layer "F.Fab")
		)
		(pad "1" smd circle
			(at -0.40005 0)
			(size 0 0)
			(layers "F.Cu" "F.Mask" "F.Paste")
			(net "P3V3_AUX")
		)
		(pad "2" smd circle
			(at 0.40005 0)
			(size 0 0)
			(layers "F.Cu" "F.Mask" "F.Paste")
			(net "GND")
		)
	)
	(footprint ""
		(layer "F.Cu")
		(at 14.668246 -214.151972)
		(property "Reference" "C4418"
			(at 0 0 0)
			(layer "F.SilkS")
			(hide yes)
			(effects
				(font
					(size 1.27 1.27)
				)
			)
		)
		(property "Value" ""
			(at 0 0 0)
			(layer "F.Fab")
			(effects
				(font
					(size 1.27 1.27)
				)
			)
		)
		(duplicate_pad_numbers_are_jumpers no)
		(fp_line
			(start -0.7874 -0.4064)
			(end 0.7874 -0.4064)
			(stroke
				(width 0.1524)
				(type default)
			)
			(layer "F.SilkS")
		)
		(fp_line
			(start -0.7874 0.4064)
			(end -0.7874 -0.4064)
			(stroke
				(width 0.1524)
				(type default)
			)
			(layer "F.SilkS")
		)
		(fp_line
			(start 0.7874 -0.4064)
			(end 0.7874 0.4064)
			(stroke
				(width 0.1524)
				(type default)
			)
			(layer "F.SilkS")
		)
		(fp_line
			(start 0.7874 0.4064)
			(end -0.7874 0.4064)
			(stroke
				(width 0.1524)
				(type default)
			)
			(layer "F.SilkS")
		)
		(fp_line
			(start -0.67945 -0.305054)
			(end -0.12065 -0.305054)
			(stroke
				(width 0.1)
				(type default)
			)
			(layer "F.Fab")
		)
		(fp_line
			(start -0.67945 0.3048)
			(end -0.67945 -0.305054)
			(stroke
				(width 0.1)
				(type default)
			)
			(layer "F.Fab")
		)
		(fp_line
			(start -0.12065 -0.305054)
			(end -0.12065 -0.2794)
			(stroke
				(width 0.1)
				(type default)
			)
			(layer "F.Fab")
		)
		(fp_line
			(start -0.12065 -0.2794)
			(end 0.12065 -0.2794)
			(stroke
				(width 0.1)
				(type default)
			)
			(layer "F.Fab")
		)
		(fp_line
			(start -0.12065 0.2794)
			(end -0.12065 0.3048)
			(stroke
				(width 0.1)
				(type default)
			)
			(layer "F.Fab")
		)
		(fp_line
			(start -0.12065 0.3048)
			(end -0.67945 0.3048)
			(stroke
				(width 0.1)
				(type default)
			)
			(layer "F.Fab")
		)
		(fp_line
			(start 0.120396 0.2794)
			(end -0.12065 0.2794)
			(stroke
				(width 0.1)
				(type default)
			)
			(layer "F.Fab")
		)
		(fp_line
			(start 0.120396 0.3048)
			(end 0.120396 0.2794)
			(stroke
				(width 0.1)
				(type default)
			)
			(layer "F.Fab")
		)
		(fp_line
			(start 0.12065 -0.3048)
			(end 0.67945 -0.3048)
			(stroke
				(width 0.1)
				(type default)
			)
			(layer "F.Fab")
		)
		(fp_line
			(start 0.12065 -0.2794)
			(end 0.12065 -0.3048)
			(stroke
				(width 0.1)
				(type default)
			)
			(layer "F.Fab")
		)
		(fp_line
			(start 0.67945 -0.3048)
			(end 0.67945 0.3048)
			(stroke
				(width 0.1)
				(type default)
			)
			(layer "F.Fab")
		)
		(fp_line
			(start 0.67945 0.3048)
			(end 0.120396 0.3048)
			(stroke
				(width 0.1)
				(type default)
			)
			(layer "F.Fab")
		)
		(pad "1" smd circle
			(at -0.40005 0)
			(size 0 0)
			(layers "F.Cu" "F.Mask" "F.Paste")
			(net "PEX0_P1V8_PLL_EN")
		)
		(pad "2" smd circle
			(at 0.40005 0)
			(size 0 0)
			(layers "F.Cu" "F.Mask" "F.Paste")
			(net "GND")
		)
	)
)
